# T6G (Grand Teton) — schematic netlist excerpt (pin names and nets, part order shuffled) for the footprints in the layout excerpt that follows; sources: Cadence DE-HDL packaged netlist, KiCad conversion of 04192023_DAF0TMB3IC0_F0TG_MB_C_brd_V02_OCP.brd

R718  Q_RES  1K 1% CHIP  pkg 0402LF  page 238 : A = MB_FRU_ADDR1 ; B = GND
R4060  Q_RES  0 5% EMPTY  pkg 0402LF  page 140 : A = P3V3_OCP_V3_2_EN_R ; B = P3V3_OCP_EN_2_R

(kicad_pcb
	(version 20260206)
	(generator "pcbnew")
	(generator_version "10.0")
	(general
		(thickness 1.6)
		(legacy_teardrops no)
	)
	(paper "A4")
	(title_block
		(title "04192023_DAF0TMB3IC0_F0TG_MB_C_brd_V02_OCP.brd")
		(comment 1 "Grand Teton / footprints 3602-3603 of 8354")
	)
	(layers
		(0 "F.Cu" signal "TOP")
		(4 "In1.Cu" signal "GND")
		(6 "In2.Cu" signal "IN1")
		(8 "In3.Cu" signal "GND1")
		(10 "In4.Cu" signal "IN2")
		(12 "In5.Cu" signal "GND2")
		(14 "In6.Cu" signal "IN3")
		(16 "In7.Cu" signal "GND3")
		(18 "In8.Cu" signal "VCC")
		(20 "In9.Cu" signal "VCC1")
		(22 "In10.Cu" signal "GND4")
		(24 "In11.Cu" signal "IN4")
		(26 "In12.Cu" signal "GND5")
		(28 "In13.Cu" signal "IN5")
		(30 "In14.Cu" signal "GND6")
		(32 "In15.Cu" signal "IN6")
		(34 "In16.Cu" signal "GND7")
		(2 "B.Cu" signal "BOTTOM")
		(9 "F.Adhes" user "F.Adhesive")
		(11 "B.Adhes" user "B.Adhesive")
		(13 "F.Paste" user "Package Geometry/Pastemask Top")
		(15 "B.Paste" user "Package Geometry/Pastemask Bottom")
		(5 "F.SilkS" user "Ref Des/Silkscreen Top")
		(7 "B.SilkS" user "Ref Des/Silkscreen Bottom")
		(1 "F.Mask" user "Board Geometry/Soldermask Top")
		(3 "B.Mask" user "Board Geometry/Soldermask Bottom")
		(17 "Dwgs.User" user "User.Drawings")
		(19 "Cmts.User" user "User.Comments")
		(21 "Eco1.User" user "User.Eco1")
		(23 "Eco2.User" user "User.Eco2")
		(25 "Edge.Cuts" user "Board Geometry/Outline")
		(27 "Margin" user)
		(31 "F.CrtYd" user "Package Geometry/Place Bound Top")
		(29 "B.CrtYd" user "Package Geometry/Place Bound Bottom")
		(35 "F.Fab" user "Ref Des/Assembly Top")
		(33 "B.Fab" user "Ref Des/Assembly Bottom")
	)
	(footprint ""
		(layer "F.Cu")
		(at 59.33313 -39.007034 90)
		(property "Reference" "R4060"
			(at 0 0 90)
			(layer "F.SilkS")
			(hide yes)
			(effects
				(font
					(size 1.27 1.27)
				)
			)
		)
		(property "Value" ""
			(at 0 0 90)
			(layer "F.Fab")
			(effects
				(font
					(size 1.27 1.27)
				)
			)
		)
		(duplicate_pad_numbers_are_jumpers no)
		(fp_line
			(start 0.7874 -0.4064)
			(end 0.7874 0.4064)
			(stroke
				(width 0.1524)
				(type default)
			)
			(layer "F.SilkS")
		)
		(fp_line
			(start -0.7874 -0.4064)
			(end 0.7874 -0.4064)
			(stroke
				(width 0.1524)
				(type default)
			)
			(layer "F.SilkS")
		)
		(fp_line
			(start 0.7874 0.4064)
			(end -0.7874 0.4064)
			(stroke
				(width 0.1524)
				(type default)
			)
			(layer "F.SilkS")
		)
		(fp_line
			(start -0.7874 0.4064)
			(end -0.7874 -0.4064)
			(stroke
				(width 0.1524)
				(type default)
			)
			(layer "F.SilkS")
		)
		(fp_line
			(start -0.12065 -0.305054)
			(end -0.12065 -0.2794)
			(stroke
				(width 0.1)
				(type default)
			)
			(layer "F.Fab")
		)
		(fp_line
			(start -0.67945 -0.305054)
			(end -0.12065 -0.305054)
			(stroke
				(width 0.1)
				(type default)
			)
			(layer "F.Fab")
		)
		(fp_line
			(start 0.67945 -0.3048)
			(end 0.67945 0.3048)
			(stroke
				(width 0.1)
				(type default)
			)
			(layer "F.Fab")
		)
		(fp_line
			(start 0.12065 -0.3048)
			(end 0.67945 -0.3048)
			(stroke
				(width 0.1)
				(type default)
			)
			(layer "F.Fab")
		)
		(fp_line
			(start 0.12065 -0.2794)
			(end 0.12065 -0.3048)
			(stroke
				(width 0.1)
				(type default)
			)
			(layer "F.Fab")
		)
		(fp_line
			(start -0.12065 -0.2794)
			(end 0.12065 -0.2794)
			(stroke
				(width 0.1)
				(type default)
			)
			(layer "F.Fab")
		)
		(fp_line
			(start 0.120396 0.2794)
			(end -0.12065 0.2794)
			(stroke
				(width 0.1)
				(type default)
			)
			(layer "F.Fab")
		)
		(fp_line
			(start -0.12065 0.2794)
			(end -0.12065 0.3048)
			(stroke
				(width 0.1)
				(type default)
			)
			(layer "F.Fab")
		)
		(fp_line
			(start 0.67945 0.3048)
			(end 0.120396 0.3048)
			(stroke
				(width 0.1)
				(type default)
			)
			(layer "F.Fab")
		)
		(fp_line
			(start 0.120396 0.3048)
			(end 0.120396 0.2794)
			(stroke
				(width 0.1)
				(type default)
			)
			(layer "F.Fab")
		)
		(fp_line
			(start -0.12065 0.3048)
			(end -0.67945 0.3048)
			(stroke
				(width 0.1)
				(type default)
			)
			(layer "F.Fab")
		)
		(fp_line
			(start -0.67945 0.3048)
			(end -0.67945 -0.305054)
			(stroke
				(width 0.1)
				(type default)
			)
			(layer "F.Fab")
		)
		(pad "1" smd circle
			(at -0.40005 0 90)
			(size 0 0)
			(layers "F.Cu" "F.Mask" "F.Paste")
			(net "P3V3_OCP_V3_2_EN_R")
		)
		(pad "2" smd circle
			(at 0.40005 0 90)
			(size 0 0)
			(layers "F.Cu" "F.Mask" "F.Paste")
			(net "P3V3_OCP_EN_2_R")
		)
	)
	(footprint ""
		(layer "F.Cu")
		(at 302.256698 -118.179088 180)
		(property "Reference" "R718"
			(at 0 0 180)
			(layer "F.SilkS")
			(hide yes)
			(effects
				(font
					(size 1.27 1.27)
				)
			)
		)
		(property "Value" ""
			(at 0 0 180)
			(layer "F.Fab")
			(effects
				(font
					(size 1.27 1.27)
				)
			)
		)
		(duplicate_pad_numbers_are_jumpers no)
		(fp_line
			(start 0.7874 0.4064)
			(end -0.7874 0.4064)
			(stroke
				(width 0.1524)
				(type default)
			)
			(layer "F.SilkS")
		)
		(fp_line
			(start 0.7874 -0.4064)
			(end 0.7874 0.4064)
			(stroke
				(width 0.1524)
				(type default)
			)
			(layer "F.SilkS")
		)
		(fp_line
			(start -0.7874 0.4064)
			(end -0.7874 -0.4064)
			(stroke
				(width 0.1524)
				(type default)
			)
			(layer "F.SilkS")
		)
		(fp_line
			(start -0.7874 -0.4064)
			(end 0.7874 -0.4064)
			(stroke
				(width 0.1524)
				(type default)
			)
			(layer "F.SilkS")
		)
		(fp_line
			(start 0.67945 0.3048)
			(end 0.120396 0.3048)
			(stroke
				(width 0.1)
				(type default)
			)
			(layer "F.Fab")
		)
		(fp_line
			(start 0.67945 -0.3048)
			(end 0.67945 0.3048)
			(stroke
				(width 0.1)
				(type default)
			)
			(layer "F.Fab")
		)
		(fp_line
			(start 0.12065 -0.2794)
			(end 0.12065 -0.3048)
			(stroke
				(width 0.1)
				(type default)
			)
			(layer "F.Fab")
		)
		(fp_line
			(start 0.12065 -0.3048)
			(end 0.67945 -0.3048)
			(stroke
				(width 0.1)
				(type default)
			)
			(layer "F.Fab")
		)
		(fp_line
			(start 0.120396 0.3048)
			(end 0.120396 0.2794)
			(stroke
				(width 0.1)
				(type default)
			)
			(layer "F.Fab")
		)
		(fp_line
			(start 0.120396 0.2794)
			(end -0.12065 0.2794)
			(stroke
				(width 0.1)
				(type default)
			)
			(layer "F.Fab")
		)
		(fp_line
			(start -0.12065 0.3048)
			(end -0.67945 0.3048)
			(stroke
				(width 0.1)
				(type default)
			)
			(layer "F.Fab")
		)
		(fp_line
			(start -0.12065 0.2794)
			(end -0.12065 0.3048)
			(stroke
				(width 0.1)
				(type default)
			)
			(layer "F.Fab")
		)
		(fp_line
			(start -0.12065 -0.2794)
			(end 0.12065 -0.2794)
			(stroke
				(width 0.1)
				(type default)
			)
			(layer "F.Fab")
		)
		(fp_line
			(start -0.12065 -0.305054)
			(end -0.12065 -0.2794)
			(stroke
				(width 0.1)
				(type default)
			)
			(layer "F.Fab")
		)
		(fp_line
			(start -0.67945 0.3048)
			(end -0.67945 -0.305054)
			(stroke
				(width 0.1)
				(type default)
			)
			(layer "F.Fab")
		)
		(fp_line
			(start -0.67945 -0.305054)
			(end -0.12065 -0.305054)
			(stroke
				(width 0.1)
				(type default)
			)
			(layer "F.Fab")
		)
		(pad "1" smd circle
			(at -0.40005 0 180)
			(size 0 0)
			(layers "F.Cu" "F.Mask" "F.Paste")
			(net "MB_FRU_ADDR1")
		)
		(pad "2" smd circle
			(at 0.40005 0 180)
			(size 0 0)
			(layers "F.Cu" "F.Mask" "F.Paste")
			(net "GND")
		)
	)
)
